(kicad_pcb
	(version 20260206)
	(generator "pcbnew")
	(generator_version "10.0")
	(general
		(thickness 1.6)
		(legacy_teardrops no)
	)
	(paper "A4")
	(title_block
		(title "timecard-production-celestica-r4006 — R4006-B0001-02_R01.brd")
		(comment 1 "Time Appliance Project (Time Card) / footprints 300-304 of 1113")
	)
	(layers
		(0 "F.Cu" signal "TOP")
		(4 "In1.Cu" signal "L02_GND1")
		(6 "In2.Cu" signal "L03_SIG1")
		(8 "In3.Cu" signal "L04_GND2")
		(10 "In4.Cu" signal "L05_VCC1")
		(12 "In5.Cu" signal "L06_VCC2")
		(14 "In6.Cu" signal "L07_GND3")
		(16 "In7.Cu" signal "L08_SIG2")
		(18 "In8.Cu" signal "L09_GND4")
		(2 "B.Cu" signal "BOTTOM")
		(9 "F.Adhes" user "F.Adhesive")
		(11 "B.Adhes" user "B.Adhesive")
		(13 "F.Paste" user "Package Geometry/Pastemask Top")
		(15 "B.Paste" user "Package Geometry/Pastemask Bottom")
		(5 "F.SilkS" user "Ref Des/Silkscreen Top")
		(7 "B.SilkS" user "Ref Des/Silkscreen Bottom")
		(1 "F.Mask" user "Board Geometry/Soldermask Top")
		(3 "B.Mask" user "Board Geometry/Soldermask Bottom")
		(17 "Dwgs.User" user "User.Drawings")
		(19 "Cmts.User" user "User.Comments")
		(21 "Eco1.User" user "User.Eco1")
		(23 "Eco2.User" user "User.Eco2")
		(25 "Edge.Cuts" user "Board Geometry/Outline")
		(27 "Margin" user)
		(31 "F.CrtYd" user "Package Geometry/Place Bound Top")
		(29 "B.CrtYd" user "Package Geometry/Place Bound Bottom")
		(35 "F.Fab" user "Ref Des/Assembly Top")
		(33 "B.Fab" user "Ref Des/Assembly Bottom")
	)
	(footprint ""
		(layer "F.Cu")
		(at 42.672 -76.581)
		(property "Reference" "U41"
			(at -0.889 2.83337 0)
			(unlocked yes)
			(layer "F.SilkS")
			(effects
				(font
					(size 0.7874 0.5842)
					(thickness 0.1524)
				)
			)
		)
		(property "Value" ""
			(at 0 0 0)
			(layer "F.Fab")
			(effects
				(font
					(size 1.27 1.27)
				)
			)
		)
		(property "Device Type" "ISL80101IRAJZ_DFN10-G222-10136A"
			(at 0.276606 2.583688 0)
			(unlocked yes)
			(layer "F.Fab")
			(hide yes)
			(effects
				(font
					(size 0.7874 0.5842)
					(thickness 0.1524)
				)
			)
		)
		(property "User Part Number" "PARTNUM*"
			(at 0.276606 3.517646 0)
			(unlocked yes)
			(layer "Cmts.User")
			(hide yes)
			(effects
				(font
					(size 0.7874 0.5842)
					(thickness 0.1524)
				)
			)
		)
		(duplicate_pad_numbers_are_jumpers no)
		(fp_line
			(start -2.290318 -1.779016)
			(end 2.290318 -1.779016)
			(stroke
				(width 0.1)
				(type default)
			)
			(layer "F.SilkS")
		)
		(fp_line
			(start -2.290318 1.779016)
			(end -2.290318 -1.779016)
			(stroke
				(width 0.1)
				(type default)
			)
			(layer "F.SilkS")
		)
		(fp_line
			(start 2.290318 -1.779016)
			(end 2.290318 1.779016)
			(stroke
				(width 0.1)
				(type default)
			)
			(layer "F.SilkS")
		)
		(fp_line
			(start 2.290318 1.779016)
			(end -2.290318 1.779016)
			(stroke
				(width 0.1)
				(type default)
			)
			(layer "F.SilkS")
		)
		(fp_poly
			(pts
				(arc
					(start -2.553462 -1.023112)
					(mid -3.315462 -1.023112)
					(end -2.553462 -1.023112)
				)
			)
			(stroke
				(width 0)
				(type default)
			)
			(fill yes)
			(layer "F.SilkS")
		)
		(fp_poly
			(pts
				(xy -0.7239 -0.1016)
				(arc
					(start -0.7239 -0.6477)
					(mid -0.290295 -0.468095)
					(end -0.4699 -0.9017)
				)
				(xy 0.7239 -0.9017) (xy 0.7239 -0.1016)
			)
			(stroke
				(width 0)
				(type default)
			)
			(fill yes)
			(layer "F.Paste")
		)
		(fp_poly
			(pts
				(xy -0.7239 0.1016) (xy 0.7239 0.1016) (xy 0.7239 0.635)
				(arc
					(start 0.723646 0.635254)
					(mid 0.645086 0.463711)
					(end 0.4699 0.3937)
				)
				(arc
					(start 0.4699 0.3937)
					(mid 0.290295 0.468095)
					(end 0.2159 0.6477)
				)
				(arc
					(start 0.2159 0.6477)
					(mid 0.284118 0.820908)
					(end 0.45212 0.901192)
				)
				(xy 0.45212 0.9017) (xy -0.7239 0.9017)
			)
			(stroke
				(width 0)
				(type default)
			)
			(fill yes)
			(layer "F.Paste")
		)
		(fp_poly
			(pts
				(xy -2.544318 2.033016) (xy 2.544318 2.033016) (xy 2.544318 -2.033016) (xy -2.544318 -2.033016)
			)
			(stroke
				(width 0)
				(type default)
			)
			(fill no)
			(layer "F.CrtYd")
		)
		(fp_line
			(start -1.525016 -1.525016)
			(end 1.525016 -1.525016)
			(stroke
				(width 0.1)
				(type default)
			)
			(layer "F.Fab")
		)
		(fp_line
			(start -1.525016 1.525016)
			(end -1.525016 -1.525016)
			(stroke
				(width 0.1)
				(type default)
			)
			(layer "F.Fab")
		)
		(fp_line
			(start 1.525016 -1.525016)
			(end 1.525016 1.525016)
			(stroke
				(width 0.1)
				(type default)
			)
			(layer "F.Fab")
		)
		(fp_line
			(start 1.525016 1.525016)
			(end -1.525016 1.525016)
			(stroke
				(width 0.1)
				(type default)
			)
			(layer "F.Fab")
		)
		(fp_poly
			(pts
				(arc
					(start -2.553462 -1.023112)
					(mid -3.315462 -1.023112)
					(end -2.553462 -1.023112)
				)
			)
			(stroke
				(width 0)
				(type default)
			)
			(fill yes)
			(layer "F.Fab")
		)
		(fp_text user "5"
			(at -2.825496 1.184402 0)
			(unlocked yes)
			(layer "F.SilkS")
			(effects
				(font
					(size 0.635 0.4064)
					(thickness 0.1524)
				)
			)
		)
		(fp_text user "6"
			(at 2.667 1.04775 0)
			(unlocked yes)
			(layer "F.SilkS")
			(effects
				(font
					(size 0.635 0.4064)
					(thickness 0.1524)
				)
			)
		)
		(fp_text user "10"
			(at 2.69875 -0.762 90)
			(unlocked yes)
			(layer "F.SilkS")
			(effects
				(font
					(size 0.635 0.4064)
					(thickness 0.1524)
				)
			)
		)
		(fp_text user "5"
			(at -2.54 1.25095 0)
			(unlocked yes)
			(layer "F.Fab")
			(effects
				(font
					(size 0.635 0.4064)
					(thickness 0.1524)
				)
			)
		)
		(fp_text user "10"
			(at 2.286 -1.67005 0)
			(unlocked yes)
			(layer "F.Fab")
			(effects
				(font
					(size 0.635 0.4064)
					(thickness 0.1524)
				)
			)
		)
		(fp_text user "6"
			(at 2.413 1.37795 0)
			(unlocked yes)
			(layer "F.Fab")
			(effects
				(font
					(size 0.635 0.4064)
					(thickness 0.1524)
				)
			)
		)
		(pad "1" smd circle
			(at -1.515618 -1.000252 180)
			(size 0 0)
			(layers "F.Cu" "F.Mask" "F.Paste")
			(net "XP3R3V_FT4232")
		)
		(pad "2" smd rect
			(at -1.515618 -0.500126)
			(size 1.0414 0.3048)
			(layers "F.Cu" "F.Mask" "F.Paste")
			(net "XP3R3V_FT4232")
		)
		(pad "3" smd rect
			(at -1.515618 0)
			(size 1.0414 0.3048)
			(layers "F.Cu" "F.Mask" "F.Paste")
			(net "UNNAMED_525_ISL80101IRAJZDFN10_")
		)
		(pad "4" smd rect
			(at -1.515618 0.500126)
			(size 1.0414 0.3048)
			(layers "F.Cu" "F.Mask" "F.Paste")
			(net "XP3R3V_FT_PG")
		)
		(pad "5" smd circle
			(at -1.515618 1.000252)
			(size 0 0)
			(layers "F.Cu" "F.Mask" "F.Paste")
			(net "SG")
		)
		(pad "6" smd circle
			(at 1.515618 1.000252)
			(size 0 0)
			(layers "F.Cu" "F.Mask" "F.Paste")
			(net "UNNAMED_525_CAPACITOR_I18_1")
		)
		(pad "7" smd rect
			(at 1.515618 0.500126)
			(size 1.0414 0.3048)
			(layers "F.Cu" "F.Mask" "F.Paste")
			(net "UNNAMED_525_CAPACITOR_I14_1")
		)
		(pad "8" smd rect
			(at 1.515618 0)
			(size 1.0414 0.3048)
			(layers "F.Cu" "F.Mask" "F.Paste")
			(net "Net_788")
		)
		(pad "9" smd rect
			(at 1.515618 -0.500126)
			(size 1.0414 0.3048)
			(layers "F.Cu" "F.Mask" "F.Paste")
			(net "UNNAMED_525_CAPACITOR_I16_1")
		)
		(pad "10" smd circle
			(at 1.515618 -1.000252 180)
			(size 0 0)
			(layers "F.Cu" "F.Mask" "F.Paste")
			(net "UNNAMED_525_CAPACITOR_I16_1")
		)
		(pad "11" smd rect
			(at 0 0)
			(size 1.4478 1.8034)
			(layers "F.Cu" "F.Mask" "F.Paste")
			(net "SG")
		)
	)
	(footprint ""
		(layer "F.Cu")
		(at 85.725 -67.31)
		(property "Reference" "TP18"
			(at -1.2954 -0.85725 0)
			(unlocked yes)
			(layer "F.SilkS")
			(effects
				(font
					(size 0.635 0.4064)
					(thickness 0.1524)
				)
				(justify left)
			)
		)
		(property "Value" ""
			(at 0 0 0)
			(layer "F.Fab")
			(effects
				(font
					(size 1.27 1.27)
				)
			)
		)
		(property "Device Type" "TP_PIONT-TP010CT020B030_PTH-TPA"
			(at -1.341882 0.996696 0)
			(unlocked yes)
			(layer "F.Fab")
			(hide yes)
			(effects
				(font
					(size 0.7874 0.5842)
					(thickness 0.000001)
				)
				(justify left)
			)
		)
		(duplicate_pad_numbers_are_jumpers no)
		(fp_poly
			(pts
				(arc
					(start 0.889 0)
					(mid -0.889 0)
					(end 0.889 0)
				)
			)
			(stroke
				(width 0)
				(type default)
			)
			(fill no)
			(layer "B.CrtYd")
		)
		(fp_poly
			(pts
				(arc
					(start 0.889 0)
					(mid -0.889 0)
					(end 0.889 0)
				)
			)
			(stroke
				(width 0)
				(type default)
			)
			(fill no)
			(layer "F.CrtYd")
		)
		(pad "1" thru_hole circle
			(at 0 0)
			(size 0.508 0.508)
			(drill 0.254)
			(layers "*.Cu" "*.Mask")
			(remove_unused_layers no)
			(net "R_BNO080_BOOT_N")
			(clearance 0.1016)
			(padstack
				(mode front_inner_back)
				(layer "Inner"
					(shape circle)
					(size 0.508 0.508)
					(clearance 0.1016)
				)
				(layer "B.Cu"
					(shape circle)
					(size 0.762 0.762)
					(clearance -0.0254)
				)
			)
		)
	)
	(footprint ""
		(layer "F.Cu")
		(at 140.9192 -20.1168)
		(property "Reference" "C242"
			(at -3.8862 -1.30683 0)
			(unlocked yes)
			(layer "F.SilkS")
			(effects
				(font
					(size 0.7874 0.5842)
					(thickness 0.1524)
				)
			)
		)
		(property "Value" "VAL*"
			(at 0.0762 2.067306 0)
			(unlocked yes)
			(layer "F.Fab")
			(hide yes)
			(effects
				(font
					(size 0.7874 0.5842)
					(thickness 0.1524)
				)
			)
		)
		(property "Tolerance" "TOL*"
			(at 0.0762 3.032506 0)
			(unlocked yes)
			(layer "Cmts.User")
			(hide yes)
			(effects
				(font
					(size 0.7874 0.5842)
					(thickness 0.1524)
				)
			)
		)
		(property "User Part Number" "PARTNUM*"
			(at 0.1016 4.023106 0)
			(unlocked yes)
			(layer "Cmts.User")
			(hide yes)
			(effects
				(font
					(size 0.7874 0.5842)
					(thickness 0.1524)
				)
			)
		)
		(property "Device Type" "CAPACITOR-G105-0B104-EK,0.1UF,A"
			(at 0.0508 1.127506 0)
			(unlocked yes)
			(layer "F.Fab")
			(hide yes)
			(effects
				(font
					(size 0.7874 0.5842)
					(thickness 0.1524)
				)
			)
		)
		(duplicate_pad_numbers_are_jumpers no)
		(fp_line
			(start -1.143 -0.5588)
			(end -1.143 0.5588)
			(stroke
				(width 0.1)
				(type default)
			)
			(layer "F.SilkS")
		)
		(fp_line
			(start -1.143 0.5588)
			(end 1.143 0.5588)
			(stroke
				(width 0.1)
				(type default)
			)
			(layer "F.SilkS")
		)
		(fp_line
			(start 1.143 -0.5588)
			(end -1.143 -0.5588)
			(stroke
				(width 0.1)
				(type default)
			)
			(layer "F.SilkS")
		)
		(fp_line
			(start 1.143 0.5588)
			(end 1.143 -0.5588)
			(stroke
				(width 0.1)
				(type default)
			)
			(layer "F.SilkS")
		)
		(fp_rect
			(start 1.143 -0.5588)
			(end -1.143 0.5588)
			(stroke
				(width 0)
				(type default)
			)
			(fill no)
			(layer "F.CrtYd")
		)
		(fp_line
			(start -0.508 -0.3048)
			(end -0.508 0.3048)
			(stroke
				(width 0.1)
				(type default)
			)
			(layer "F.Fab")
		)
		(fp_line
			(start -0.508 0.3048)
			(end 0.508 0.3048)
			(stroke
				(width 0.1)
				(type default)
			)
			(layer "F.Fab")
		)
		(fp_line
			(start 0.508 -0.3048)
			(end -0.508 -0.3048)
			(stroke
				(width 0.1)
				(type default)
			)
			(layer "F.Fab")
		)
		(fp_line
			(start 0.508 0.3048)
			(end 0.508 -0.3048)
			(stroke
				(width 0.1)
				(type default)
			)
			(layer "F.Fab")
		)
		(pad "1" smd rect
			(at -0.5334 0)
			(size 0.7112 0.6096)
			(layers "F.Cu" "F.Mask" "F.Paste")
			(net "XP2R5V_FPGA")
		)
		(pad "2" smd rect
			(at 0.5334 0)
			(size 0.7112 0.6096)
			(layers "F.Cu" "F.Mask" "F.Paste")
			(net "SG")
		)
		(zone
			(layer "F.Cu")
			(hatch none 0.5)
			(connect_pads
				(clearance 0)
			)
			(min_thickness 0.25)
			(keepout
				(tracks allowed)
				(vias not_allowed)
				(pads allowed)
				(copperpour not_allowed)
				(footprints allowed)
			)
			(placement
				(enabled no)
				(sheetname "")
			)
			(fill
				(thermal_gap 0.5)
				(thermal_bridge_width 0.5)
				(island_removal_mode 0)
			)
			(polygon
				(pts
					(xy 140.9954 -20.4216) (xy 140.843 -20.4216) (xy 140.843 -19.812) (xy 140.9954 -19.812)
				)
			)
		)
	)
	(footprint ""
		(layer "F.Cu")
		(at 143.891 -21.8186 180)
		(property "Reference" "C228"
			(at -3.175 0.74803 0)
			(unlocked yes)
			(layer "F.SilkS")
			(effects
				(font
					(size 0.7874 0.5842)
					(thickness 0.1524)
				)
			)
		)
		(property "Value" "VAL*"
			(at 0.0762 3.134106 180)
			(unlocked yes)
			(layer "F.Fab")
			(hide yes)
			(effects
				(font
					(size 0.7874 0.5842)
					(thickness 0.1524)
				)
			)
		)
		(property "Tolerance" "TOL*"
			(at 0.0762 4.048506 180)
			(unlocked yes)
			(layer "Cmts.User")
			(hide yes)
			(effects
				(font
					(size 0.7874 0.5842)
					(thickness 0.1524)
				)
			)
		)
		(property "User Part Number" "PARTNUM*"
			(at 0.1016 5.013706 180)
			(unlocked yes)
			(layer "Cmts.User")
			(hide yes)
			(effects
				(font
					(size 0.7874 0.5842)
					(thickness 0.1524)
				)
			)
		)
		(property "Device Type" "CAPACITOR-G107-0F106-EM,10UF,2A"
			(at 0.0508 2.194306 180)
			(unlocked yes)
			(layer "F.Fab")
			(hide yes)
			(effects
				(font
					(size 0.7874 0.5842)
					(thickness 0.1524)
				)
			)
		)
		(duplicate_pad_numbers_are_jumpers no)
		(fp_line
			(start 1.5748 0.9398)
			(end 1.5748 -0.9398)
			(stroke
				(width 0.1)
				(type default)
			)
			(layer "F.SilkS")
		)
		(fp_line
			(start 1.5748 -0.9398)
			(end -1.5748 -0.9398)
			(stroke
				(width 0.1)
				(type default)
			)
			(layer "F.SilkS")
		)
		(fp_line
			(start -1.5748 0.9398)
			(end 1.5748 0.9398)
			(stroke
				(width 0.1)
				(type default)
			)
			(layer "F.SilkS")
		)
		(fp_line
			(start -1.5748 -0.9398)
			(end -1.5748 0.9398)
			(stroke
				(width 0.1)
				(type default)
			)
			(layer "F.SilkS")
		)
		(fp_rect
			(start -1.5748 0.9398)
			(end 1.5748 -0.9398)
			(stroke
				(width 0)
				(type default)
			)
			(fill no)
			(layer "F.CrtYd")
		)
		(fp_line
			(start 1.016 0.635)
			(end 1.016 -0.635)
			(stroke
				(width 0.1)
				(type default)
			)
			(layer "F.Fab")
		)
		(fp_line
			(start 1.016 -0.635)
			(end -1.016 -0.635)
			(stroke
				(width 0.1)
				(type default)
			)
			(layer "F.Fab")
		)
		(fp_line
			(start -1.016 0.635)
			(end 1.016 0.635)
			(stroke
				(width 0.1)
				(type default)
			)
			(layer "F.Fab")
		)
		(fp_line
			(start -1.016 -0.635)
			(end -1.016 0.635)
			(stroke
				(width 0.1)
				(type default)
			)
			(layer "F.Fab")
		)
		(pad "1" smd rect
			(at -0.8382 0 180)
			(size 0.9652 1.3716)
			(layers "F.Cu" "F.Mask" "F.Paste")
			(net "UNNAMED_515_CAPACITOR_I130_1")
		)
		(pad "2" smd rect
			(at 0.8382 0 180)
			(size 0.9652 1.3716)
			(layers "F.Cu" "F.Mask" "F.Paste")
			(net "SG")
		)
		(zone
			(layer "F.Cu")
			(hatch none 0.5)
			(connect_pads
				(clearance 0)
			)
			(min_thickness 0.25)
			(keepout
				(tracks allowed)
				(vias not_allowed)
				(pads allowed)
				(copperpour not_allowed)
				(footprints allowed)
			)
			(placement
				(enabled no)
				(sheetname "")
			)
			(fill
				(thermal_gap 0.5)
				(thermal_bridge_width 0.5)
				(island_removal_mode 0)
			)
			(polygon
				(pts
					(xy 144.1196 -22.4536) (xy 143.6624 -22.4536) (xy 143.6624 -21.1836) (xy 144.1196 -21.1836)
				)
			)
		)
	)
	(footprint ""
		(layer "F.Cu")
		(at 144.78 -24.384 -90)
		(property "Reference" "L13"
			(at -1.8415 0.08763 90)
			(unlocked yes)
			(layer "F.SilkS")
			(effects
				(font
					(size 0.7874 0.5842)
					(thickness 0.1524)
				)
				(justify left)
			)
		)
		(property "Value" "VAL*"
			(at -0.9398 3.70967 270)
			(unlocked yes)
			(layer "F.Fab")
			(hide yes)
			(effects
				(font
					(size 0.7874 0.5842)
					(thickness 0.1524)
				)
				(justify left)
			)
		)
		(property "Tolerance" "TOL*"
			(at -0.9906 5.00507 270)
			(unlocked yes)
			(layer "Cmts.User")
			(hide yes)
			(effects
				(font
					(size 0.7874 0.5842)
					(thickness 0.1524)
				)
				(justify left)
			)
		)
		(property "User Part Number" "PARTNUM*"
			(at -2.54 2.46507 270)
			(unlocked yes)
			(layer "Cmts.User")
			(hide yes)
			(effects
				(font
					(size 0.7874 0.5842)
					(thickness 0.1524)
				)
				(justify left)
			)
		)
		(property "Device Type" "FERRITEBEAD-G191-10101-01,26OHA"
			(at -0.9906 1.22047 270)
			(unlocked yes)
			(layer "F.Fab")
			(hide yes)
			(effects
				(font
					(size 0.7874 0.5842)
					(thickness 0.1524)
				)
				(justify left)
			)
		)
		(duplicate_pad_numbers_are_jumpers no)
		(fp_line
			(start -1.3208 0.7112)
			(end -1.3208 -0.7112)
			(stroke
				(width 0.1)
				(type default)
			)
			(layer "F.SilkS")
		)
		(fp_line
			(start 1.3208 0.7112)
			(end -1.3208 0.7112)
			(stroke
				(width 0.1)
				(type default)
			)
			(layer "F.SilkS")
		)
		(fp_line
			(start -1.3208 -0.7112)
			(end 1.3208 -0.7112)
			(stroke
				(width 0.1)
				(type default)
			)
			(layer "F.SilkS")
		)
		(fp_line
			(start 1.3208 -0.7112)
			(end 1.3208 0.7112)
			(stroke
				(width 0.1)
				(type default)
			)
			(layer "F.SilkS")
		)
		(fp_rect
			(start -1.3208 -0.7112)
			(end 1.3208 0.7112)
			(stroke
				(width 0)
				(type default)
			)
			(fill no)
			(layer "F.CrtYd")
		)
		(fp_line
			(start -0.8128 0.4572)
			(end -0.8128 -0.4572)
			(stroke
				(width 0.1)
				(type default)
			)
			(layer "F.Fab")
		)
		(fp_line
			(start 0.8128 0.4572)
			(end -0.8128 0.4572)
			(stroke
				(width 0.1)
				(type default)
			)
			(layer "F.Fab")
		)
		(fp_line
			(start -0.8128 -0.4572)
			(end 0.8128 -0.4572)
			(stroke
				(width 0.1)
				(type default)
			)
			(layer "F.Fab")
		)
		(fp_line
			(start 0.8128 -0.4572)
			(end 0.8128 0.4572)
			(stroke
				(width 0.1)
				(type default)
			)
			(layer "F.Fab")
		)
		(pad "1" smd rect
			(at -0.6858 0 270)
			(size 0.762 0.8636)
			(layers "F.Cu" "F.Mask" "F.Paste")
			(net "XP3R3V")
		)
		(pad "2" smd rect
			(at 0.6858 0 270)
			(size 0.762 0.8636)
			(layers "F.Cu" "F.Mask" "F.Paste")
			(net "UNNAMED_515_CAPACITOR_I130_1")
		)
		(zone
			(layer "F.Cu")
			(hatch none 0.5)
			(connect_pads
				(clearance 0)
			)
			(min_thickness 0.25)
			(keepout
				(tracks allowed)
				(vias not_allowed)
				(pads allowed)
				(copperpour not_allowed)
				(footprints allowed)
			)
			(placement
				(enabled no)
				(sheetname "")
			)
			(fill
				(thermal_gap 0.5)
				(thermal_bridge_width 0.5)
				(island_removal_mode 0)
			)
			(polygon
				(pts
					(xy 145.2372 -24.5364) (xy 144.3228 -24.5364) (xy 144.3228 -24.2316) (xy 145.2372 -24.2316)
				)
			)
		)
	)
)
